(kicad_pcb
	(version 20260206)
	(generator "pcbnew")
	(generator_version "10.0")
	(general
		(thickness 1.6)
		(legacy_teardrops no)
	)
	(paper "A4")
	(title_block
		(title "04192023_DAF0TMB3IC0_F0TG_MB_C_brd_V02_OCP.brd")
		(comment 1 "Grand Teton / footprints 7340-7345 of 8354")
	)
	(layers
		(0 "F.Cu" signal "TOP")
		(4 "In1.Cu" signal "GND")
		(6 "In2.Cu" signal "IN1")
		(8 "In3.Cu" signal "GND1")
		(10 "In4.Cu" signal "IN2")
		(12 "In5.Cu" signal "GND2")
		(14 "In6.Cu" signal "IN3")
		(16 "In7.Cu" signal "GND3")
		(18 "In8.Cu" signal "VCC")
		(20 "In9.Cu" signal "VCC1")
		(22 "In10.Cu" signal "GND4")
		(24 "In11.Cu" signal "IN4")
		(26 "In12.Cu" signal "GND5")
		(28 "In13.Cu" signal "IN5")
		(30 "In14.Cu" signal "GND6")
		(32 "In15.Cu" signal "IN6")
		(34 "In16.Cu" signal "GND7")
		(2 "B.Cu" signal "BOTTOM")
		(9 "F.Adhes" user "F.Adhesive")
		(11 "B.Adhes" user "B.Adhesive")
		(13 "F.Paste" user "Package Geometry/Pastemask Top")
		(15 "B.Paste" user "Package Geometry/Pastemask Bottom")
		(5 "F.SilkS" user "Ref Des/Silkscreen Top")
		(7 "B.SilkS" user "Ref Des/Silkscreen Bottom")
		(1 "F.Mask" user "Board Geometry/Soldermask Top")
		(3 "B.Mask" user "Board Geometry/Soldermask Bottom")
		(17 "Dwgs.User" user "User.Drawings")
		(19 "Cmts.User" user "User.Comments")
		(21 "Eco1.User" user "User.Eco1")
		(23 "Eco2.User" user "User.Eco2")
		(25 "Edge.Cuts" user "Board Geometry/Outline")
		(27 "Margin" user)
		(31 "F.CrtYd" user "Package Geometry/Place Bound Top")
		(29 "B.CrtYd" user "Package Geometry/Place Bound Bottom")
		(35 "F.Fab" user "Ref Des/Assembly Top")
		(33 "B.Fab" user "Ref Des/Assembly Bottom")
	)
	(footprint ""
		(layer "B.Cu")
		(at 170.12158 -50.107088 180)
		(property "Reference" "C9922"
			(at 0 0 0)
			(layer "B.SilkS")
			(hide yes)
			(effects
				(font
					(size 1.27 1.27)
				)
				(justify mirror)
			)
		)
		(property "Value" ""
			(at 0 0 0)
			(layer "B.Fab")
			(effects
				(font
					(size 1.27 1.27)
				)
				(justify mirror)
			)
		)
		(duplicate_pad_numbers_are_jumpers no)
		(fp_line
			(start 1.2954 0.5842)
			(end 1.2954 -0.5842)
			(stroke
				(width 0.1524)
				(type default)
			)
			(layer "B.SilkS")
		)
		(fp_line
			(start 1.2954 -0.5842)
			(end -1.2954 -0.5842)
			(stroke
				(width 0.1524)
				(type default)
			)
			(layer "B.SilkS")
		)
		(fp_line
			(start -1.2954 0.5842)
			(end 1.2954 0.5842)
			(stroke
				(width 0.1524)
				(type default)
			)
			(layer "B.SilkS")
		)
		(fp_line
			(start -1.2954 -0.5842)
			(end -1.2954 0.5842)
			(stroke
				(width 0.1524)
				(type default)
			)
			(layer "B.SilkS")
		)
		(fp_line
			(start 1.1938 0.4064)
			(end 1.1938 -0.4064)
			(stroke
				(width 0.1)
				(type default)
			)
			(layer "B.Fab")
		)
		(fp_line
			(start 1.1938 -0.4064)
			(end 0.8636 -0.4064)
			(stroke
				(width 0.1)
				(type default)
			)
			(layer "B.Fab")
		)
		(fp_line
			(start 0.8636 0.4572)
			(end 0.8636 0.4064)
			(stroke
				(width 0.1)
				(type default)
			)
			(layer "B.Fab")
		)
		(fp_line
			(start 0.8636 0.4064)
			(end 1.1938 0.4064)
			(stroke
				(width 0.1)
				(type default)
			)
			(layer "B.Fab")
		)
		(fp_line
			(start 0.8636 -0.4064)
			(end 0.8636 -0.4572)
			(stroke
				(width 0.1)
				(type default)
			)
			(layer "B.Fab")
		)
		(fp_line
			(start 0.8636 -0.4572)
			(end -0.8636 -0.4572)
			(stroke
				(width 0.1)
				(type default)
			)
			(layer "B.Fab")
		)
		(fp_line
			(start -0.8636 0.4572)
			(end 0.8636 0.4572)
			(stroke
				(width 0.1)
				(type default)
			)
			(layer "B.Fab")
		)
		(fp_line
			(start -0.8636 0.4064)
			(end -0.8636 0.4572)
			(stroke
				(width 0.1)
				(type default)
			)
			(layer "B.Fab")
		)
		(fp_line
			(start -0.8636 -0.4064)
			(end -1.1938 -0.4064)
			(stroke
				(width 0.1)
				(type default)
			)
			(layer "B.Fab")
		)
		(fp_line
			(start -0.8636 -0.4572)
			(end -0.8636 -0.4064)
			(stroke
				(width 0.1)
				(type default)
			)
			(layer "B.Fab")
		)
		(fp_line
			(start -1.1938 0.4064)
			(end -0.8636 0.4064)
			(stroke
				(width 0.1)
				(type default)
			)
			(layer "B.Fab")
		)
		(fp_line
			(start -1.1938 -0.4064)
			(end -1.1938 0.4064)
			(stroke
				(width 0.1)
				(type default)
			)
			(layer "B.Fab")
		)
		(pad "1" smd rect
			(at 0.7366 0 90)
			(size 0.7112 0.8128)
			(layers "B.Cu" "B.Mask" "B.Paste")
			(net "P3V3_M2_0")
		)
		(pad "2" smd rect
			(at -0.7366 0 90)
			(size 0.7112 0.8128)
			(layers "B.Cu" "B.Mask" "B.Paste")
			(net "GND")
		)
	)
	(footprint ""
		(layer "B.Cu")
		(at 13.650468 -135.44931 90)
		(property "Reference" "C95"
			(at 0 0 90)
			(layer "B.SilkS")
			(hide yes)
			(effects
				(font
					(size 1.27 1.27)
				)
				(justify mirror)
			)
		)
		(property "Value" ""
			(at 0 0 90)
			(layer "B.Fab")
			(effects
				(font
					(size 1.27 1.27)
				)
				(justify mirror)
			)
		)
		(duplicate_pad_numbers_are_jumpers no)
		(fp_line
			(start 0.7874 -0.4064)
			(end -0.7874 -0.4064)
			(stroke
				(width 0.1524)
				(type default)
			)
			(layer "B.SilkS")
		)
		(fp_line
			(start -0.7874 -0.4064)
			(end -0.7874 0.4064)
			(stroke
				(width 0.1524)
				(type default)
			)
			(layer "B.SilkS")
		)
		(fp_line
			(start 0.7874 0.4064)
			(end 0.7874 -0.4064)
			(stroke
				(width 0.1524)
				(type default)
			)
			(layer "B.SilkS")
		)
		(fp_line
			(start -0.7874 0.4064)
			(end 0.7874 0.4064)
			(stroke
				(width 0.1524)
				(type default)
			)
			(layer "B.SilkS")
		)
		(fp_line
			(start 0.67945 -0.305054)
			(end 0.12065 -0.305054)
			(stroke
				(width 0.1)
				(type default)
			)
			(layer "B.Fab")
		)
		(fp_line
			(start 0.12065 -0.305054)
			(end 0.12065 -0.2794)
			(stroke
				(width 0.1)
				(type default)
			)
			(layer "B.Fab")
		)
		(fp_line
			(start -0.12065 -0.3048)
			(end -0.67945 -0.3048)
			(stroke
				(width 0.1)
				(type default)
			)
			(layer "B.Fab")
		)
		(fp_line
			(start -0.67945 -0.3048)
			(end -0.67945 0.3048)
			(stroke
				(width 0.1)
				(type default)
			)
			(layer "B.Fab")
		)
		(fp_line
			(start 0.12065 -0.2794)
			(end -0.12065 -0.2794)
			(stroke
				(width 0.1)
				(type default)
			)
			(layer "B.Fab")
		)
		(fp_line
			(start -0.12065 -0.2794)
			(end -0.12065 -0.3048)
			(stroke
				(width 0.1)
				(type default)
			)
			(layer "B.Fab")
		)
		(fp_line
			(start 0.12065 0.2794)
			(end 0.12065 0.3048)
			(stroke
				(width 0.1)
				(type default)
			)
			(layer "B.Fab")
		)
		(fp_line
			(start -0.120396 0.2794)
			(end 0.12065 0.2794)
			(stroke
				(width 0.1)
				(type default)
			)
			(layer "B.Fab")
		)
		(fp_line
			(start 0.67945 0.3048)
			(end 0.67945 -0.305054)
			(stroke
				(width 0.1)
				(type default)
			)
			(layer "B.Fab")
		)
		(fp_line
			(start 0.12065 0.3048)
			(end 0.67945 0.3048)
			(stroke
				(width 0.1)
				(type default)
			)
			(layer "B.Fab")
		)
		(fp_line
			(start -0.120396 0.3048)
			(end -0.120396 0.2794)
			(stroke
				(width 0.1)
				(type default)
			)
			(layer "B.Fab")
		)
		(fp_line
			(start -0.67945 0.3048)
			(end -0.120396 0.3048)
			(stroke
				(width 0.1)
				(type default)
			)
			(layer "B.Fab")
		)
		(pad "1" smd circle
			(at 0.40005 0 270)
			(size 0 0)
			(layers "B.Cu" "B.Mask" "B.Paste")
			(net "VFG3P3_CLK_GEN")
		)
		(pad "2" smd circle
			(at -0.40005 0 270)
			(size 0 0)
			(layers "B.Cu" "B.Mask" "B.Paste")
			(net "GND")
		)
	)
	(footprint ""
		(layer "B.Cu")
		(at 312.403236 -197.836028 -90)
		(property "Reference" "R6081"
			(at 0 0 90)
			(layer "B.SilkS")
			(hide yes)
			(effects
				(font
					(size 1.27 1.27)
				)
				(justify mirror)
			)
		)
		(property "Value" ""
			(at 0 0 90)
			(layer "B.Fab")
			(effects
				(font
					(size 1.27 1.27)
				)
				(justify mirror)
			)
		)
		(duplicate_pad_numbers_are_jumpers no)
		(fp_line
			(start -0.7874 0.4064)
			(end 0.7874 0.4064)
			(stroke
				(width 0.1524)
				(type default)
			)
			(layer "B.SilkS")
		)
		(fp_line
			(start 0.7874 0.4064)
			(end 0.7874 -0.4064)
			(stroke
				(width 0.1524)
				(type default)
			)
			(layer "B.SilkS")
		)
		(fp_line
			(start -0.7874 -0.4064)
			(end -0.7874 0.4064)
			(stroke
				(width 0.1524)
				(type default)
			)
			(layer "B.SilkS")
		)
		(fp_line
			(start 0.7874 -0.4064)
			(end -0.7874 -0.4064)
			(stroke
				(width 0.1524)
				(type default)
			)
			(layer "B.SilkS")
		)
		(fp_line
			(start -0.67945 0.3048)
			(end -0.120396 0.3048)
			(stroke
				(width 0.1)
				(type default)
			)
			(layer "B.Fab")
		)
		(fp_line
			(start -0.120396 0.3048)
			(end -0.120396 0.2794)
			(stroke
				(width 0.1)
				(type default)
			)
			(layer "B.Fab")
		)
		(fp_line
			(start 0.12065 0.3048)
			(end 0.67945 0.3048)
			(stroke
				(width 0.1)
				(type default)
			)
			(layer "B.Fab")
		)
		(fp_line
			(start 0.67945 0.3048)
			(end 0.67945 -0.305054)
			(stroke
				(width 0.1)
				(type default)
			)
			(layer "B.Fab")
		)
		(fp_line
			(start -0.120396 0.2794)
			(end 0.12065 0.2794)
			(stroke
				(width 0.1)
				(type default)
			)
			(layer "B.Fab")
		)
		(fp_line
			(start 0.12065 0.2794)
			(end 0.12065 0.3048)
			(stroke
				(width 0.1)
				(type default)
			)
			(layer "B.Fab")
		)
		(fp_line
			(start -0.12065 -0.2794)
			(end -0.12065 -0.3048)
			(stroke
				(width 0.1)
				(type default)
			)
			(layer "B.Fab")
		)
		(fp_line
			(start 0.12065 -0.2794)
			(end -0.12065 -0.2794)
			(stroke
				(width 0.1)
				(type default)
			)
			(layer "B.Fab")
		)
		(fp_line
			(start -0.67945 -0.3048)
			(end -0.67945 0.3048)
			(stroke
				(width 0.1)
				(type default)
			)
			(layer "B.Fab")
		)
		(fp_line
			(start -0.12065 -0.3048)
			(end -0.67945 -0.3048)
			(stroke
				(width 0.1)
				(type default)
			)
			(layer "B.Fab")
		)
		(fp_line
			(start 0.12065 -0.305054)
			(end 0.12065 -0.2794)
			(stroke
				(width 0.1)
				(type default)
			)
			(layer "B.Fab")
		)
		(fp_line
			(start 0.67945 -0.305054)
			(end 0.12065 -0.305054)
			(stroke
				(width 0.1)
				(type default)
			)
			(layer "B.Fab")
		)
		(pad "1" smd circle
			(at 0.40005 0 90)
			(size 0 0)
			(layers "B.Cu" "B.Mask" "B.Paste")
			(net "PVDD11_S3_P0")
		)
		(pad "2" smd circle
			(at -0.40005 0 90)
			(size 0 0)
			(layers "B.Cu" "B.Mask" "B.Paste")
			(net "SMB_CPU0_2_SCL")
		)
	)
	(footprint ""
		(layer "B.Cu")
		(at 50.214784 -408.517344 90)
		(property "Reference" "C6661"
			(at 0 0 90)
			(layer "B.SilkS")
			(hide yes)
			(effects
				(font
					(size 1.27 1.27)
				)
				(justify mirror)
			)
		)
		(property "Value" ""
			(at 0 0 90)
			(layer "B.Fab")
			(effects
				(font
					(size 1.27 1.27)
				)
				(justify mirror)
			)
		)
		(duplicate_pad_numbers_are_jumpers no)
		(fp_line
			(start 0.299974 -0.150114)
			(end -0.299974 -0.150114)
			(stroke
				(width 0.1)
				(type default)
			)
			(layer "B.Fab")
		)
		(fp_line
			(start -0.299974 -0.150114)
			(end -0.299974 0.150114)
			(stroke
				(width 0.1)
				(type default)
			)
			(layer "B.Fab")
		)
		(fp_line
			(start 0.299974 0.150114)
			(end 0.299974 -0.150114)
			(stroke
				(width 0.1)
				(type default)
			)
			(layer "B.Fab")
		)
		(fp_line
			(start -0.299974 0.150114)
			(end 0.299974 0.150114)
			(stroke
				(width 0.1)
				(type default)
			)
			(layer "B.Fab")
		)
		(pad "1" smd rect
			(at 0.2667 0 270)
			(size 0.3048 0.381)
			(layers "B.Cu" "B.Mask" "B.Paste")
			(net "P5E_CPU1_P1_TX_BUF_C_DP<0>")
		)
		(pad "2" smd rect
			(at -0.2667 0 270)
			(size 0.3048 0.381)
			(layers "B.Cu" "B.Mask" "B.Paste")
			(net "P5E_CPU1_P1_TX_BUF_DP<0>")
		)
	)
	(footprint ""
		(layer "B.Cu")
		(at 384.653282 -416.899344 90)
		(property "Reference" "C6606"
			(at 0 0 90)
			(layer "B.SilkS")
			(hide yes)
			(effects
				(font
					(size 1.27 1.27)
				)
				(justify mirror)
			)
		)
		(property "Value" ""
			(at 0 0 90)
			(layer "B.Fab")
			(effects
				(font
					(size 1.27 1.27)
				)
				(justify mirror)
			)
		)
		(duplicate_pad_numbers_are_jumpers no)
		(fp_line
			(start 0.299974 -0.150114)
			(end -0.299974 -0.150114)
			(stroke
				(width 0.1)
				(type default)
			)
			(layer "B.Fab")
		)
		(fp_line
			(start -0.299974 -0.150114)
			(end -0.299974 0.150114)
			(stroke
				(width 0.1)
				(type default)
			)
			(layer "B.Fab")
		)
		(fp_line
			(start 0.299974 0.150114)
			(end 0.299974 -0.150114)
			(stroke
				(width 0.1)
				(type default)
			)
			(layer "B.Fab")
		)
		(fp_line
			(start -0.299974 0.150114)
			(end 0.299974 0.150114)
			(stroke
				(width 0.1)
				(type default)
			)
			(layer "B.Fab")
		)
		(pad "1" smd rect
			(at 0.2667 0 270)
			(size 0.3048 0.381)
			(layers "B.Cu" "B.Mask" "B.Paste")
			(net "P5E_CPU0_P3_TX_BUF_C_DN<4>")
		)
		(pad "2" smd rect
			(at -0.2667 0 270)
			(size 0.3048 0.381)
			(layers "B.Cu" "B.Mask" "B.Paste")
			(net "P5E_CPU0_P3_TX_BUF_DN<4>")
		)
	)
	(footprint ""
		(layer "B.Cu")
		(at 191.000888 -126.861824 -90)
		(property "Reference" "R251"
			(at 0 0 90)
			(layer "B.SilkS")
			(hide yes)
			(effects
				(font
					(size 1.27 1.27)
				)
				(justify mirror)
			)
		)
		(property "Value" ""
			(at 0 0 90)
			(layer "B.Fab")
			(effects
				(font
					(size 1.27 1.27)
				)
				(justify mirror)
			)
		)
		(duplicate_pad_numbers_are_jumpers no)
		(fp_line
			(start -0.7874 0.4064)
			(end 0.7874 0.4064)
			(stroke
				(width 0.1524)
				(type default)
			)
			(layer "B.SilkS")
		)
		(fp_line
			(start 0.7874 0.4064)
			(end 0.7874 -0.4064)
			(stroke
				(width 0.1524)
				(type default)
			)
			(layer "B.SilkS")
		)
		(fp_line
			(start -0.7874 -0.4064)
			(end -0.7874 0.4064)
			(stroke
				(width 0.1524)
				(type default)
			)
			(layer "B.SilkS")
		)
		(fp_line
			(start 0.7874 -0.4064)
			(end -0.7874 -0.4064)
			(stroke
				(width 0.1524)
				(type default)
			)
			(layer "B.SilkS")
		)
		(fp_line
			(start -0.67945 0.3048)
			(end -0.120396 0.3048)
			(stroke
				(width 0.1)
				(type default)
			)
			(layer "B.Fab")
		)
		(fp_line
			(start -0.120396 0.3048)
			(end -0.120396 0.2794)
			(stroke
				(width 0.1)
				(type default)
			)
			(layer "B.Fab")
		)
		(fp_line
			(start 0.12065 0.3048)
			(end 0.67945 0.3048)
			(stroke
				(width 0.1)
				(type default)
			)
			(layer "B.Fab")
		)
		(fp_line
			(start 0.67945 0.3048)
			(end 0.67945 -0.305054)
			(stroke
				(width 0.1)
				(type default)
			)
			(layer "B.Fab")
		)
		(fp_line
			(start -0.120396 0.2794)
			(end 0.12065 0.2794)
			(stroke
				(width 0.1)
				(type default)
			)
			(layer "B.Fab")
		)
		(fp_line
			(start 0.12065 0.2794)
			(end 0.12065 0.3048)
			(stroke
				(width 0.1)
				(type default)
			)
			(layer "B.Fab")
		)
		(fp_line
			(start -0.12065 -0.2794)
			(end -0.12065 -0.3048)
			(stroke
				(width 0.1)
				(type default)
			)
			(layer "B.Fab")
		)
		(fp_line
			(start 0.12065 -0.2794)
			(end -0.12065 -0.2794)
			(stroke
				(width 0.1)
				(type default)
			)
			(layer "B.Fab")
		)
		(fp_line
			(start -0.67945 -0.3048)
			(end -0.67945 0.3048)
			(stroke
				(width 0.1)
				(type default)
			)
			(layer "B.Fab")
		)
		(fp_line
			(start -0.12065 -0.3048)
			(end -0.67945 -0.3048)
			(stroke
				(width 0.1)
				(type default)
			)
			(layer "B.Fab")
		)
		(fp_line
			(start 0.12065 -0.305054)
			(end 0.12065 -0.2794)
			(stroke
				(width 0.1)
				(type default)
			)
			(layer "B.Fab")
		)
		(fp_line
			(start 0.67945 -0.305054)
			(end 0.12065 -0.305054)
			(stroke
				(width 0.1)
				(type default)
			)
			(layer "B.Fab")
		)
		(pad "1" smd circle
			(at 0.40005 0 90)
			(size 0 0)
			(layers "B.Cu" "B.Mask" "B.Paste")
			(net "CPU0_SPD_HOST_CTRL_R1_N")
		)
		(pad "2" smd circle
			(at -0.40005 0 90)
			(size 0 0)
			(layers "B.Cu" "B.Mask" "B.Paste")
			(net "CPU0_SPD_HOST_CTRL_N")
		)
	)
)
